# S9S_MB_2U (Grand Teton) — schematic netlist excerpt (pin names and nets, part order shuffled) for the footprints in the layout excerpt that follows; sources: Cadence DE-HDL packaged netlist, KiCad conversion of 03242023_DA0F0TMBIJ0_F0T_Motherboard_J_brd_V01_OCP.brd

J3  SCONN288_ADR50017P130CC  SCONN288_ADR50017-P130CC IO  pkg DDR288S_1-1VXB  page 84
  VIN_BULK0  = P12V_S3_AUX_CPU0_NVDIMM
  RFU0  = TP_CHB_CPU0_DIMM1_FRU_0
  VIN_MGMT  = P3V3_AUX
  HSCL  = I3C_SPD_DDRABCD_CPU0_LVC1_SCL_2
  HSDA  = I3C_SPD_DDRABCD_CPU0_LVC1_SDA
  VSS0  = GND
  DQ0_A  = M_B_CPU0_SA_DQ<0>
  VSS1  = GND
  DQ1_A  = M_B_CPU0_SA_DQ<1>
  VSS2  = GND
  DQS0_A_T  = M_B_CPU0_SA_DQS_DP<0>
  DQS0_A_C  = M_B_CPU0_SA_DQS_DN<0>
  VSS3  = GND
  DQ4_A  = M_B_CPU0_SA_DQ<4>
  VSS4  = GND
  DQ5_A  = M_B_CPU0_SA_DQ<5>
  VSS5  = GND
  DQ8_A  = M_B_CPU0_SA_DQ<8>
  VSS6  = GND
  DQ9_A  = M_B_CPU0_SA_DQ<9>
  VSS7  = GND
  DQS1_A_T  = M_B_CPU0_SA_DQS_DP<1>
  DQS1_A_C  = M_B_CPU0_SA_DQS_DN<1>
  VSS8  = GND
  DQ12_A  = M_B_CPU0_SA_DQ<12>
  VSS9  = GND
  DQ13_A  = M_B_CPU0_SA_DQ<13>
  VSS10  = GND
  DQ16_A  = M_B_CPU0_SA_DQ<16>
  VSS11  = GND
  DQ17_A  = M_B_CPU0_SA_DQ<17>
  VSS12  = GND
  DQS2_A_T  = M_B_CPU0_SA_DQS_DP<2>
  DQS2_A_C  = M_B_CPU0_SA_DQS_DN<2>
  VSS13  = GND
  DQ20_A  = M_B_CPU0_SA_DQ<20>
  VSS14  = GND
  DQ21_A  = M_B_CPU0_SA_DQ<21>
  VSS15  = GND
  DQ24_A  = M_B_CPU0_SA_DQ<24>
  VSS16  = GND
  DQ25_A  = M_B_CPU0_SA_DQ<25>
  VSS17  = GND
  DQS3_A_T  = M_B_CPU0_SA_DQS_DP<3>
  DQS3_A_C  = M_B_CPU0_SA_DQS_DN<3>
  VSS18  = GND
  DQ28_A  = M_B_CPU0_SA_DQ<28>
  VSS19  = GND
  DQ29_A  = M_B_CPU0_SA_DQ<29>
  VSS20  = GND
  CB0_A  = M_B_CPU0_SA_CB<0>
  VSS21  = GND
  CB1_A  = M_B_CPU0_SA_CB<1>
  VSS22  = GND
  DQS4_A_T  = M_B_CPU0_SA_DQS_DP<4>
  DQS4_A_C  = M_B_CPU0_SA_DQS_DN<4>
  VSS23  = GND
  CB4_A  = M_B_CPU0_SA_CB<4>
  VSS24  = GND
  CB5_A  = M_B_CPU0_SA_CB<5>
  VSS25  = GND
  ALERT_N  = M_B_CPU0_ALERT_N
  VSS26  = GND
  CS0_A_N  = M_B_CPU0_SA_CS_N<0>
  VSS27  = GND
  CA0_A  = M_B_CPU0_SA_CA<0>
  VSS28  = GND
  CA2_A  = M_B_CPU0_SA_CA<2>
  VSS29  = GND
  CA4_A  = M_B_CPU0_SA_CA<4>
  VSS30  = GND
  CA6_A  = M_B_CPU0_SA_CA<6>
  VSS31  = GND
  PAR_A  = M_B_CPU0_SA_PAR
  VSS32  = GND
  CA0_B  = M_B_CPU0_SB_CA<0>
  VSS33  = GND
  CA2_B  = M_B_CPU0_SB_CA<2>
  VSS34  = GND
  CA4_B  = M_B_CPU0_SB_CA<4>
  VSS35  = GND
  CA6_B  = M_B_CPU0_SB_CA<6>
  VSS36  = GND
  CS0_B_N  = M_B_CPU0_SB_CS_N<0>
  VSS37  = GND
  \lbd||rsp_a_n\  = M_B_CPU0_SA_RSP<0>
  \lbs||rsp_b_n\  = M_B_CPU0_SB_RSP<0>
  VSS38  = GND
  CB4_B  = M_B_CPU0_SB_CB<4>
  VSS39  = GND
  CB5_B  = M_B_CPU0_SB_CB<5>
  VSS40  = GND
  \dqs9_b_t||tdqs9_b_t||dbi4_b_n\  = M_B_CPU0_SB_DQS_DP<9>
  \dqs9_b_c||tdqs9_b_c\  = M_B_CPU0_SB_DQS_DN<9>
  VSS41  = GND
  CB0_B  = M_B_CPU0_SB_CB<0>
  VSS42  = GND
  CB1_B  = M_B_CPU0_SB_CB<1>
  VSS43  = GND
  DQ0_B  = M_B_CPU0_SB_DQ<0>
  VSS44  = GND
  DQ1_B  = M_B_CPU0_SB_DQ<1>
  VSS45  = GND
  DQS0_B_T  = M_B_CPU0_SB_DQS_DP<0>
  DQS0_B_C  = M_B_CPU0_SB_DQS_DN<0>
  VSS46  = GND
  DQ4_B  = M_B_CPU0_SB_DQ<4>
  VSS47  = GND
  DQ5_B  = M_B_CPU0_SB_DQ<5>
  VSS48  = GND
  DQ8_B  = M_B_CPU0_SB_DQ<8>
  VSS49  = GND
  DQ9_B  = M_B_CPU0_SB_DQ<9>
  VSS50  = GND
  DQS1_B_T  = M_B_CPU0_SB_DQS_DP<1>
  DQS1_B_C  = M_B_CPU0_SB_DQS_DN<1>
  VSS51  = GND
  DQ12_B  = M_B_CPU0_SB_DQ<12>
  VSS52  = GND
  DQ13_B  = M_B_CPU0_SB_DQ<13>
  VSS53  = GND
  DQ16_B  = M_B_CPU0_SB_DQ<16>
  VSS54  = GND
  DQ17_B  = M_B_CPU0_SB_DQ<17>
  VSS55  = GND
  DQS2_B_T  = M_B_CPU0_SB_DQS_DP<2>
  DQS2_B_C  = M_B_CPU0_SB_DQS_DN<2>
  VSS56  = GND
  DQ20_B  = M_B_CPU0_SB_DQ<20>
  VSS57  = GND
  DQ21_B  = M_B_CPU0_SB_DQ<21>
  VSS58  = GND
  DQ24_B  = M_B_CPU0_SB_DQ<24>
  VSS59  = GND
  DQ25_B  = M_B_CPU0_SB_DQ<25>
  VSS60  = GND
  DQS3_B_T  = M_B_CPU0_SB_DQS_DP<3>
  DQS3_B_C  = M_B_CPU0_SB_DQS_DN<3>
  VSS61  = GND
  DQ28_B  = M_B_CPU0_SB_DQ<28>
  VSS62  = GND
  DQ29_B  = M_B_CPU0_SB_DQ<29>
  VSS63  = GND
  RFU1  = TP_CHB_CPU0_DIMM1_FRU_1
  VIN_BULK1  = P12V_S3_AUX_CPU0_NVDIMM
  VIN_BULK2  = P12V_S3_AUX_CPU0_NVDIMM
  \pwr_good||fail_n\  = PWRGD_CHB_CPU0_DIMM1
  HSA  = PD_CHB_CPU0_DIMM1_SAA
  RFU2  = TP_CHB_CPU0_DIMM1_FRU_2
  RFU3  = TP_CHB_CPU0_DIMM1_FRU_3
  VSS64  = GND
  DQ2_A  = M_B_CPU0_SA_DQ<2>
  VSS65  = GND
  DQ3_A  = M_B_CPU0_SA_DQ<3>
  VSS66  = GND
  \dqs5_a_c||tdqs5_a_c||dqs5_a_t||tdqs5_a_t\  = M_B_CPU0_SA_DQS_DN<5>
  \dqs5_a_t||tdqs5_a_t\  = M_B_CPU0_SA_DQS_DP<5>
  VSS67  = GND
  DQ6_A  = M_B_CPU0_SA_DQ<6>
  VSS68  = GND
  DQ7_A  = M_B_CPU0_SA_DQ<7>
  VSS69  = GND
  DQ10_A  = M_B_CPU0_SA_DQ<10>
  VSS70  = GND
  DQ11_A  = M_B_CPU0_SA_DQ<11>
  VSS71  = GND
  \dqs6_a_c||tdqs6_a_c||dqs6_a_t||tdqs6_a_t\  = M_B_CPU0_SA_DQS_DN<6>
  \dqs6_a_t||tdqs6_a_t\  = M_B_CPU0_SA_DQS_DP<6>
  VSS72  = GND
  DQ14_A  = M_B_CPU0_SA_DQ<14>
  VSS73  = GND
  DQ15_A  = M_B_CPU0_SA_DQ<15>
  VSS74  = GND
  DQ18_A  = M_B_CPU0_SA_DQ<18>
  VSS75  = GND
  DQ19_A  = M_B_CPU0_SA_DQ<19>
  VSS76  = GND
  \dqs7_a_c||tdqs7_a_c\  = M_B_CPU0_SA_DQS_DN<7>
  \dqs7_a_t||tdqs7_a_t\  = M_B_CPU0_SA_DQS_DP<7>
  VSS77  = GND
  DQ22_A  = M_B_CPU0_SA_DQ<22>
  VSS78  = GND
  DQ23_A  = M_B_CPU0_SA_DQ<23>
  VSS79  = GND
  DQ26_A  = M_B_CPU0_SA_DQ<26>
  VSS80  = GND
  DQ27_A  = M_B_CPU0_SA_DQ<27>
  VSS81  = GND
  \dqs8_a_c||tdqs8_a_c\  = M_B_CPU0_SA_DQS_DN<8>
  \dqs8_a_t||tdqs8_a_t\  = M_B_CPU0_SA_DQS_DP<8>
  VSS82  = GND
  DQ30_A  = M_B_CPU0_SA_DQ<30>
  VSS83  = GND
  DQ31_A  = M_B_CPU0_SA_DQ<31>
  VSS84  = GND
  CB2_A  = M_B_CPU0_SA_CB<2>
  VSS85  = GND
  CB3_A  = M_B_CPU0_SA_CB<3>
  VSS86  = GND
  \dqs9_a_c||tdqs9_a_c\  = M_B_CPU0_SA_DQS_DN<9>
  \dqs9_a_t||tdqs9_a_t\  = M_B_CPU0_SA_DQS_DP<9>
  VSS87  = GND
  CB6_A  = M_B_CPU0_SA_CB<6>
  VSS88  = GND
  CB7_A  = M_B_CPU0_SA_CB<7>
  VSS89  = GND
  RESET_N  = RST_M_AB_CPU0_FPGA_N
  VSS90  = GND
  CS1_A_N  = M_B_CPU0_SA_CS_N<1>
  VSS91  = GND
  CA1_A  = M_B_CPU0_SA_CA<1>
  VSS92  = GND
  CA3_A  = M_B_CPU0_SA_CA<3>
  VSS93  = GND
  CA5_A  = M_B_CPU0_SA_CA<5>
  VSS94  = GND
  CK_T  = M_B_CPU0_CLK_DP<0>
  CK_C  = M_B_CPU0_CLK_DN<0>
  VSS95  = GND
  RFU4  = TP_CHB_CPU0_DIMM1_FRU_4
  CA1_B  = M_B_CPU0_SB_CA<1>
  VSS96  = GND
  CA3_B  = M_B_CPU0_SB_CA<3>
  VSS97  = GND
  CA5_B  = M_B_CPU0_SB_CA<5>
  VSS98  = GND
  PAR_B  = M_B_CPU0_SB_PAR
  VSS99  = GND
  CS1_B_N  = M_B_CPU0_SB_CS_N<1>
  VSS100  = GND
  RFU5  = TP_CHB_CPU0_DIMM1_FRU_5
  RFU6  = TP_CHB_CPU0_DIMM1_FRU_6
  VSS101  = GND
  CB6_B  = M_B_CPU0_SB_CB<6>
  VSS102  = GND
  CB7_B  = M_B_CPU0_SB_CB<7>
  VSS103  = GND
  DQS4_B_C  = M_B_CPU0_SB_DQS_DN<4>
  DQS4_B_T  = M_B_CPU0_SB_DQS_DP<4>
  VSS104  = GND
  CB2_B  = M_B_CPU0_SB_CB<2>
  VSS105  = GND
  CB3_B  = M_B_CPU0_SB_CB<3>
  VSS106  = GND
  DQ2_B  = M_B_CPU0_SB_DQ<2>
  VSS107  = GND
  DQ3_B  = M_B_CPU0_SB_DQ<3>
  VSS108  = GND
  \dqs5_b_c||tdqs5_b_c\  = M_B_CPU0_SB_DQS_DN<5>
  \dqs5_b_t||tdqs5_b_t\  = M_B_CPU0_SB_DQS_DP<5>
  VSS109  = GND
  DQ6_B  = M_B_CPU0_SB_DQ<6>
  VSS110  = GND
  DQ7_B  = M_B_CPU0_SB_DQ<7>
  VSS111  = GND
  DQ10_B  = M_B_CPU0_SB_DQ<10>
  VSS112  = GND
  DQ11_B  = M_B_CPU0_SB_DQ<11>
  VSS113  = GND
  \dqs6_b_c||tdqs6_b_c\  = M_B_CPU0_SB_DQS_DN<6>
  \dqs6_b_t||tdqs6_b_t\  = M_B_CPU0_SB_DQS_DP<6>
  VSS114  = GND
  DQ14_B  = M_B_CPU0_SB_DQ<14>
  VSS115  = GND
  DQ15_B  = M_B_CPU0_SB_DQ<15>
  VSS116  = GND
  DQ18_B  = M_B_CPU0_SB_DQ<18>
  VSS117  = GND
  DQ19_B  = M_B_CPU0_SB_DQ<19>
  VSS118  = GND
  \dqs7_b_c||tdqs7_b_c\  = M_B_CPU0_SB_DQS_DN<7>
  \dqs7_b_t||tdqs7_b_t\  = M_B_CPU0_SB_DQS_DP<7>
  VSS119  = GND
  DQ22_B  = M_B_CPU0_SB_DQ<22>
  VSS120  = GND
  DQ23_B  = M_B_CPU0_SB_DQ<23>
  VSS121  = GND
  DQ26_B  = M_B_CPU0_SB_DQ<26>
  VSS122  = GND
  DQ27_B  = M_B_CPU0_SB_DQ<27>
  VSS123  = GND
  \dqs8_b_c||tdqs8_b_c\  = M_B_CPU0_SB_DQS_DN<8>
  \dqs8_b_t||tdqs8_b_t\  = M_B_CPU0_SB_DQS_DP<8>
  VSS124  = GND
  DQ30_B  = M_B_CPU0_SB_DQ<30>
  VSS125  = GND
  DQ31_B  = M_B_CPU0_SB_DQ<31>
  VSS126  = GND
  G1  = GND
  G2  = GND
  G3  = GND

(kicad_pcb
	(version 20260206)
	(generator "pcbnew")
	(generator_version "10.0")
	(general
		(thickness 1.6)
		(legacy_teardrops no)
	)
	(paper "A4")
	(title_block
		(title "03242023_DA0F0TMBIJ0_F0T_Motherboard_J_brd_V01_OCP.brd")
		(comment 1 "Grand Teton / footprint 2048 of 6105 (J3), pads 183-228 of 291")
	)
	(layers
		(0 "F.Cu" signal "TOP")
		(4 "In1.Cu" signal "GND")
		(6 "In2.Cu" signal "IN1")
		(8 "In3.Cu" signal "GND1")
		(10 "In4.Cu" signal "IN2")
		(12 "In5.Cu" signal "GND2")
		(14 "In6.Cu" signal "IN3")
		(16 "In7.Cu" signal "GND3")
		(18 "In8.Cu" signal "VCC")
		(20 "In9.Cu" signal "VCC1")
		(22 "In10.Cu" signal "GND4")
		(24 "In11.Cu" signal "IN4")
		(26 "In12.Cu" signal "GND5")
		(28 "In13.Cu" signal "IN5")
		(30 "In14.Cu" signal "GND6")
		(32 "In15.Cu" signal "IN6")
		(34 "In16.Cu" signal "GND7")
		(2 "B.Cu" signal "BOTTOM")
		(9 "F.Adhes" user "F.Adhesive")
		(11 "B.Adhes" user "B.Adhesive")
		(13 "F.Paste" user "Package Geometry/Pastemask Top")
		(15 "B.Paste" user "Package Geometry/Pastemask Bottom")
		(5 "F.SilkS" user "Ref Des/Silkscreen Top")
		(7 "B.SilkS" user "Ref Des/Silkscreen Bottom")
		(1 "F.Mask" user "Board Geometry/Soldermask Top")
		(3 "B.Mask" user "Board Geometry/Soldermask Bottom")
		(17 "Dwgs.User" user "User.Drawings")
		(19 "Cmts.User" user "User.Comments")
		(21 "Eco1.User" user "User.Eco1")
		(23 "Eco2.User" user "User.Eco2")
		(25 "Edge.Cuts" user "Board Geometry/Outline")
		(27 "Margin" user)
		(31 "F.CrtYd" user "Package Geometry/Place Bound Top")
		(29 "B.CrtYd" user "Package Geometry/Place Bound Bottom")
		(35 "F.Fab" user "Ref Des/Assembly Top")
		(33 "B.Fab" user "Ref Des/Assembly Bottom")
	)
	(footprint ""
		(layer "F.Cu")
		(at 288.305748 -258.091686)
		(property "Reference" "J3"
			(at -3.683 -81.702148 0)
			(unlocked yes)
			(layer "F.SilkS")
			(effects
				(font
					(size 0.7874 0.5842)
					(thickness 0.1524)
				)
				(justify left)
			)
		)
		(property "Value" ""
			(at 0 0 0)
			(layer "F.Fab")
			(effects
				(font
					(size 1.27 1.27)
				)
			)
		)
		(duplicate_pad_numbers_are_jumpers no)
		(pad "183" smd rect
			(at 2.050034 -31.025084 270)
			(size 0.519938 1.4986)
			(layers "F.Cu" "F.Mask" "F.Paste")
			(net "M_B_CPU0_SA_DQ<23>")
		)
		(pad "184" smd rect
			(at 2.050034 -30.174946 270)
			(size 0.519938 1.4986)
			(layers "F.Cu" "F.Mask" "F.Paste")
			(net "GND")
		)
		(pad "185" smd rect
			(at 2.050034 -29.325062 270)
			(size 0.519938 1.4986)
			(layers "F.Cu" "F.Mask" "F.Paste")
			(net "M_B_CPU0_SA_DQ<26>")
		)
		(pad "186" smd rect
			(at 2.050034 -28.474924 270)
			(size 0.519938 1.4986)
			(layers "F.Cu" "F.Mask" "F.Paste")
			(net "GND")
		)
		(pad "187" smd rect
			(at 2.050034 -27.62504 270)
			(size 0.519938 1.4986)
			(layers "F.Cu" "F.Mask" "F.Paste")
			(net "M_B_CPU0_SA_DQ<27>")
		)
		(pad "188" smd rect
			(at 2.050034 -26.774902 270)
			(size 0.519938 1.4986)
			(layers "F.Cu" "F.Mask" "F.Paste")
			(net "GND")
		)
		(pad "189" smd rect
			(at 2.050034 -25.925018 270)
			(size 0.519938 1.4986)
			(layers "F.Cu" "F.Mask" "F.Paste")
			(net "M_B_CPU0_SA_DQS_DN<8>")
		)
		(pad "190" smd rect
			(at 2.050034 -25.07488 270)
			(size 0.519938 1.4986)
			(layers "F.Cu" "F.Mask" "F.Paste")
			(net "M_B_CPU0_SA_DQS_DP<8>")
		)
		(pad "191" smd rect
			(at 2.050034 -24.224996 270)
			(size 0.519938 1.4986)
			(layers "F.Cu" "F.Mask" "F.Paste")
			(net "GND")
		)
		(pad "192" smd rect
			(at 2.050034 -23.375112 270)
			(size 0.519938 1.4986)
			(layers "F.Cu" "F.Mask" "F.Paste")
			(net "M_B_CPU0_SA_DQ<30>")
		)
		(pad "193" smd rect
			(at 2.050034 -22.524974 270)
			(size 0.519938 1.4986)
			(layers "F.Cu" "F.Mask" "F.Paste")
			(net "GND")
		)
		(pad "194" smd rect
			(at 2.050034 -21.67509 270)
			(size 0.519938 1.4986)
			(layers "F.Cu" "F.Mask" "F.Paste")
			(net "M_B_CPU0_SA_DQ<31>")
		)
		(pad "195" smd rect
			(at 2.050034 -20.824952 270)
			(size 0.519938 1.4986)
			(layers "F.Cu" "F.Mask" "F.Paste")
			(net "GND")
		)
		(pad "196" smd rect
			(at 2.050034 -19.975068 270)
			(size 0.519938 1.4986)
			(layers "F.Cu" "F.Mask" "F.Paste")
			(net "M_B_CPU0_SA_CB<2>")
		)
		(pad "197" smd rect
			(at 2.050034 -19.12493 270)
			(size 0.519938 1.4986)
			(layers "F.Cu" "F.Mask" "F.Paste")
			(net "GND")
		)
		(pad "198" smd rect
			(at 2.050034 -18.275046 270)
			(size 0.519938 1.4986)
			(layers "F.Cu" "F.Mask" "F.Paste")
			(net "M_B_CPU0_SA_CB<3>")
		)
		(pad "199" smd rect
			(at 2.050034 -17.424908 270)
			(size 0.519938 1.4986)
			(layers "F.Cu" "F.Mask" "F.Paste")
			(net "GND")
		)
		(pad "200" smd rect
			(at 2.050034 -16.575024 270)
			(size 0.519938 1.4986)
			(layers "F.Cu" "F.Mask" "F.Paste")
			(net "M_B_CPU0_SA_DQS_DN<9>")
		)
		(pad "201" smd rect
			(at 2.050034 -15.724886 270)
			(size 0.519938 1.4986)
			(layers "F.Cu" "F.Mask" "F.Paste")
			(net "M_B_CPU0_SA_DQS_DP<9>")
		)
		(pad "202" smd rect
			(at 2.050034 -14.875002 270)
			(size 0.519938 1.4986)
			(layers "F.Cu" "F.Mask" "F.Paste")
			(net "GND")
		)
		(pad "203" smd rect
			(at 2.050034 -14.025118 270)
			(size 0.519938 1.4986)
			(layers "F.Cu" "F.Mask" "F.Paste")
			(net "M_B_CPU0_SA_CB<6>")
		)
		(pad "204" smd rect
			(at 2.050034 -13.17498 270)
			(size 0.519938 1.4986)
			(layers "F.Cu" "F.Mask" "F.Paste")
			(net "GND")
		)
		(pad "205" smd rect
			(at 2.050034 -12.325096 270)
			(size 0.519938 1.4986)
			(layers "F.Cu" "F.Mask" "F.Paste")
			(net "M_B_CPU0_SA_CB<7>")
		)
		(pad "206" smd rect
			(at 2.050034 -11.474958 270)
			(size 0.519938 1.4986)
			(layers "F.Cu" "F.Mask" "F.Paste")
			(net "GND")
		)
		(pad "207" smd rect
			(at 2.050034 -10.625074 270)
			(size 0.519938 1.4986)
			(layers "F.Cu" "F.Mask" "F.Paste")
			(net "RST_M_AB_CPU0_FPGA_N")
		)
		(pad "208" smd rect
			(at 2.050034 -9.774936 270)
			(size 0.519938 1.4986)
			(layers "F.Cu" "F.Mask" "F.Paste")
			(net "GND")
		)
		(pad "209" smd rect
			(at 2.050034 -8.925052 270)
			(size 0.519938 1.4986)
			(layers "F.Cu" "F.Mask" "F.Paste")
			(net "M_B_CPU0_SA_CS_N<1>")
		)
		(pad "210" smd rect
			(at 2.050034 -8.074914 270)
			(size 0.519938 1.4986)
			(layers "F.Cu" "F.Mask" "F.Paste")
			(net "GND")
		)
		(pad "211" smd rect
			(at 2.050034 -7.22503 270)
			(size 0.519938 1.4986)
			(layers "F.Cu" "F.Mask" "F.Paste")
			(net "M_B_CPU0_SA_CA<1>")
		)
		(pad "212" smd rect
			(at 2.050034 -6.374892 270)
			(size 0.519938 1.4986)
			(layers "F.Cu" "F.Mask" "F.Paste")
			(net "GND")
		)
		(pad "213" smd rect
			(at 2.050034 -5.525008 270)
			(size 0.519938 1.4986)
			(layers "F.Cu" "F.Mask" "F.Paste")
			(net "M_B_CPU0_SA_CA<3>")
		)
		(pad "214" smd rect
			(at 2.050034 -4.675124 270)
			(size 0.519938 1.4986)
			(layers "F.Cu" "F.Mask" "F.Paste")
			(net "GND")
		)
		(pad "215" smd rect
			(at 2.050034 -3.824986 270)
			(size 0.519938 1.4986)
			(layers "F.Cu" "F.Mask" "F.Paste")
			(net "M_B_CPU0_SA_CA<5>")
		)
		(pad "216" smd rect
			(at 2.050034 -2.975102 270)
			(size 0.519938 1.4986)
			(layers "F.Cu" "F.Mask" "F.Paste")
			(net "GND")
		)
		(pad "217" smd rect
			(at 2.050034 -2.124964 270)
			(size 0.519938 1.4986)
			(layers "F.Cu" "F.Mask" "F.Paste")
			(net "M_B_CPU0_CLK_DP<0>")
		)
		(pad "218" smd rect
			(at 2.050034 -1.27508 270)
			(size 0.519938 1.4986)
			(layers "F.Cu" "F.Mask" "F.Paste")
			(net "M_B_CPU0_CLK_DN<0>")
		)
		(pad "219" smd rect
			(at 2.050034 -0.424942 270)
			(size 0.519938 1.4986)
			(layers "F.Cu" "F.Mask" "F.Paste")
			(net "GND")
		)
		(pad "220" smd rect
			(at 2.050034 5.525008 270)
			(size 0.519938 1.4986)
			(layers "F.Cu" "F.Mask" "F.Paste")
			(net "TP_CHB_CPU0_DIMM1_FRU_4")
		)
		(pad "221" smd rect
			(at 2.050034 6.374892 270)
			(size 0.519938 1.4986)
			(layers "F.Cu" "F.Mask" "F.Paste")
			(net "M_B_CPU0_SB_CA<1>")
		)
		(pad "222" smd rect
			(at 2.050034 7.22503 270)
			(size 0.519938 1.4986)
			(layers "F.Cu" "F.Mask" "F.Paste")
			(net "GND")
		)
		(pad "223" smd rect
			(at 2.050034 8.074914 270)
			(size 0.519938 1.4986)
			(layers "F.Cu" "F.Mask" "F.Paste")
			(net "M_B_CPU0_SB_CA<3>")
		)
		(pad "224" smd rect
			(at 2.050034 8.925052 270)
			(size 0.519938 1.4986)
			(layers "F.Cu" "F.Mask" "F.Paste")
			(net "GND")
		)
		(pad "225" smd rect
			(at 2.050034 9.774936 270)
			(size 0.519938 1.4986)
			(layers "F.Cu" "F.Mask" "F.Paste")
			(net "M_B_CPU0_SB_CA<5>")
		)
		(pad "226" smd rect
			(at 2.050034 10.625074 270)
			(size 0.519938 1.4986)
			(layers "F.Cu" "F.Mask" "F.Paste")
			(net "GND")
		)
		(pad "227" smd rect
			(at 2.050034 11.474958 270)
			(size 0.519938 1.4986)
			(layers "F.Cu" "F.Mask" "F.Paste")
			(net "M_B_CPU0_SB_PAR")
		)
		(pad "228" smd rect
			(at 2.050034 12.325096 270)
			(size 0.519938 1.4986)
			(layers "F.Cu" "F.Mask" "F.Paste")
			(net "GND")
		)
	)
)
